(kicad_pcb
	(version 20260206)
	(generator "pcbnew")
	(generator_version "10.0")
	(general
		(thickness 1.6)
		(legacy_teardrops no)
	)
	(paper "A4")
	(title_block
		(title "01162023_DA0F0TEBIF0_F0T_Expander_BD_F_brd_V02_OCP.brd")
		(comment 1 "Grand Teton / footprint 6602 of 9728 (PEX1), pads 1654-1767 of 2397")
	)
	(layers
		(0 "F.Cu" signal "TOP")
		(4 "In1.Cu" signal "GND")
		(6 "In2.Cu" signal "VCC")
		(8 "In3.Cu" signal "VCC1")
		(10 "In4.Cu" signal "GND1")
		(12 "In5.Cu" signal "IN1")
		(14 "In6.Cu" signal "GND2")
		(16 "In7.Cu" signal "IN2")
		(18 "In8.Cu" signal "GND3")
		(20 "In9.Cu" signal "IN3")
		(22 "In10.Cu" signal "GND4")
		(24 "In11.Cu" signal "IN4")
		(26 "In12.Cu" signal "GND5")
		(28 "In13.Cu" signal "IN5")
		(30 "In14.Cu" signal "GND6")
		(32 "In15.Cu" signal "IN6")
		(34 "In16.Cu" signal "GND7")
		(2 "B.Cu" signal "BOTTOM")
		(9 "F.Adhes" user "F.Adhesive")
		(11 "B.Adhes" user "B.Adhesive")
		(13 "F.Paste" user "Package Geometry/Pastemask Top")
		(15 "B.Paste" user "Package Geometry/Pastemask Bottom")
		(5 "F.SilkS" user "Ref Des/Silkscreen Top")
		(7 "B.SilkS" user "Ref Des/Silkscreen Bottom")
		(1 "F.Mask" user "Board Geometry/Soldermask Top")
		(3 "B.Mask" user "Board Geometry/Soldermask Bottom")
		(17 "Dwgs.User" user "User.Drawings")
		(19 "Cmts.User" user "User.Comments")
		(21 "Eco1.User" user "User.Eco1")
		(23 "Eco2.User" user "User.Eco2")
		(25 "Edge.Cuts" user "Board Geometry/Outline")
		(27 "Margin" user)
		(31 "F.CrtYd" user "Package Geometry/Place Bound Top")
		(29 "B.CrtYd" user "Package Geometry/Place Bound Bottom")
		(35 "F.Fab" user "Ref Des/Assembly Top")
		(33 "B.Fab" user "Ref Des/Assembly Bottom")
	)
	(footprint ""
		(layer "F.Cu")
		(at 175.749966 -295.89984)
		(property "Reference" "PEX1"
			(at -3.353562 35.593274 0)
			(unlocked yes)
			(layer "F.SilkS")
			(effects
				(font
					(size 2.032 1.524)
					(thickness 0.1524)
				)
				(justify left)
			)
		)
		(property "Value" ""
			(at 0 0 0)
			(layer "F.Fab")
			(effects
				(font
					(size 1.27 1.27)
				)
			)
		)
		(duplicate_pad_numbers_are_jumpers no)
		(pad "E41" smd circle
			(at 15.200122 -18.999962)
			(size 0.4572 0.4572)
			(layers "F.Cu" "F.Mask" "F.Paste")
			(net "GND")
		)
		(pad "E42" smd circle
			(at 16.150082 -18.999962)
			(size 0.4572 0.4572)
			(layers "F.Cu" "F.Mask" "F.Paste")
			(net "GND")
		)
		(pad "E43" smd circle
			(at 17.100042 -18.999962)
			(size 0.4572 0.4572)
			(layers "F.Cu" "F.Mask" "F.Paste")
			(net "GND")
		)
		(pad "E44" smd circle
			(at 18.050002 -18.999962)
			(size 0.4572 0.4572)
			(layers "F.Cu" "F.Mask" "F.Paste")
			(net "GND")
		)
		(pad "E45" smd circle
			(at 18.999962 -18.999962)
			(size 0.4572 0.4572)
			(layers "F.Cu" "F.Mask" "F.Paste")
			(net "GND")
		)
		(pad "E46" smd circle
			(at 19.949922 -18.999962)
			(size 0.4572 0.4572)
			(layers "F.Cu" "F.Mask" "F.Paste")
			(net "GND")
		)
		(pad "E47" smd circle
			(at 20.899882 -18.999962)
			(size 0.4572 0.4572)
			(layers "F.Cu" "F.Mask" "F.Paste")
			(net "GND")
		)
		(pad "E48" smd circle
			(at 21.850096 -18.999962)
			(size 0.4572 0.4572)
			(layers "F.Cu" "F.Mask" "F.Paste")
			(net "P5E_PEX1_STN4_TX_DP<71>")
		)
		(pad "E49" smd circle
			(at 22.800056 -18.999962)
			(size 0.4572 0.4572)
			(layers "F.Cu" "F.Mask" "F.Paste")
			(net "P5E_PEX1_STN4_TX_DN<71>")
		)
		(pad "F1" smd circle
			(at -22.800056 -18.050002)
			(size 0.4572 0.4572)
			(layers "F.Cu" "F.Mask" "F.Paste")
			(net "GND")
		)
		(pad "F2" smd circle
			(at -21.850096 -18.050002)
			(size 0.4572 0.4572)
			(layers "F.Cu" "F.Mask" "F.Paste")
			(net "GND")
		)
		(pad "F3" smd circle
			(at -20.899882 -18.050002)
			(size 0.4572 0.4572)
			(layers "F.Cu" "F.Mask" "F.Paste")
			(net "P5E_PEX1_STN7_TX_DN<123>")
		)
		(pad "F4" smd circle
			(at -19.949922 -18.050002)
			(size 0.4572 0.4572)
			(layers "F.Cu" "F.Mask" "F.Paste")
			(net "GND")
		)
		(pad "F5" smd circle
			(at -18.999962 -18.050002)
			(size 0.4572 0.4572)
			(layers "F.Cu" "F.Mask" "F.Paste")
			(net "P5E_PEX1_STN7_TX_DN<125>")
		)
		(pad "F6" smd circle
			(at -18.050002 -18.050002)
			(size 0.4572 0.4572)
			(layers "F.Cu" "F.Mask" "F.Paste")
			(net "GND")
		)
		(pad "F7" smd circle
			(at -17.100042 -18.050002)
			(size 0.4572 0.4572)
			(layers "F.Cu" "F.Mask" "F.Paste")
			(net "P5E_PEX1_STN7_TX_DN<127>")
		)
		(pad "F8" smd circle
			(at -16.150082 -18.050002)
			(size 0.4572 0.4572)
			(layers "F.Cu" "F.Mask" "F.Paste")
			(net "GND")
		)
		(pad "F9" smd circle
			(at -15.200122 -18.050002)
			(size 0.4572 0.4572)
			(layers "F.Cu" "F.Mask" "F.Paste")
			(net "P5E_PEX1_STN6_TX_DN<110>")
		)
		(pad "F10" smd circle
			(at -14.249908 -18.050002)
			(size 0.4572 0.4572)
			(layers "F.Cu" "F.Mask" "F.Paste")
			(net "GND")
		)
		(pad "F11" smd circle
			(at -13.299948 -18.050002)
			(size 0.4572 0.4572)
			(layers "F.Cu" "F.Mask" "F.Paste")
			(net "P5E_PEX1_STN6_TX_DN<108>")
		)
		(pad "F12" smd circle
			(at -12.349988 -18.050002)
			(size 0.4572 0.4572)
			(layers "F.Cu" "F.Mask" "F.Paste")
			(net "GND")
		)
		(pad "F13" smd circle
			(at -11.400028 -18.050002)
			(size 0.4572 0.4572)
			(layers "F.Cu" "F.Mask" "F.Paste")
			(net "P5E_PEX1_STN6_TX_DN<106>")
		)
		(pad "F14" smd circle
			(at -10.450068 -18.050002)
			(size 0.4572 0.4572)
			(layers "F.Cu" "F.Mask" "F.Paste")
			(net "GND")
		)
		(pad "F15" smd circle
			(at -9.500108 -18.050002)
			(size 0.4572 0.4572)
			(layers "F.Cu" "F.Mask" "F.Paste")
			(net "P5E_PEX1_STN6_TX_DN<104>")
		)
		(pad "F16" smd circle
			(at -8.549894 -18.050002)
			(size 0.4572 0.4572)
			(layers "F.Cu" "F.Mask" "F.Paste")
			(net "GND")
		)
		(pad "F17" smd circle
			(at -7.599934 -18.050002)
			(size 0.4572 0.4572)
			(layers "F.Cu" "F.Mask" "F.Paste")
			(net "P5E_PEX1_STN6_TX_DN<102>")
		)
		(pad "F18" smd circle
			(at -6.649974 -18.050002)
			(size 0.4572 0.4572)
			(layers "F.Cu" "F.Mask" "F.Paste")
			(net "GND")
		)
		(pad "F19" smd circle
			(at -5.700014 -18.050002)
			(size 0.4572 0.4572)
			(layers "F.Cu" "F.Mask" "F.Paste")
			(net "P5E_PEX1_STN6_TX_DN<100>")
		)
		(pad "F20" smd circle
			(at -4.750054 -18.050002)
			(size 0.4572 0.4572)
			(layers "F.Cu" "F.Mask" "F.Paste")
			(net "GND")
		)
		(pad "F21" smd circle
			(at -3.800094 -18.050002)
			(size 0.4572 0.4572)
			(layers "F.Cu" "F.Mask" "F.Paste")
			(net "P5E_PEX1_STN6_TX_DN<98>")
		)
		(pad "F22" smd circle
			(at -2.84988 -18.050002)
			(size 0.4572 0.4572)
			(layers "F.Cu" "F.Mask" "F.Paste")
			(net "GND")
		)
		(pad "F23" smd circle
			(at -1.89992 -18.050002)
			(size 0.4572 0.4572)
			(layers "F.Cu" "F.Mask" "F.Paste")
			(net "P5E_PEX1_STN6_TX_DN<96>")
		)
		(pad "F24" smd circle
			(at -0.94996 -18.050002)
			(size 0.4572 0.4572)
			(layers "F.Cu" "F.Mask" "F.Paste")
			(net "GND")
		)
		(pad "F25" smd circle
			(at 0 -18.050002)
			(size 0.4572 0.4572)
			(layers "F.Cu" "F.Mask" "F.Paste")
			(net "P5E_PEX1_STN5_TX_DN<81>")
		)
		(pad "F26" smd circle
			(at 0.94996 -18.050002)
			(size 0.4572 0.4572)
			(layers "F.Cu" "F.Mask" "F.Paste")
			(net "GND")
		)
		(pad "F27" smd circle
			(at 1.89992 -18.050002)
			(size 0.4572 0.4572)
			(layers "F.Cu" "F.Mask" "F.Paste")
			(net "P5E_PEX1_STN5_TX_DN<83>")
		)
		(pad "F28" smd circle
			(at 2.84988 -18.050002)
			(size 0.4572 0.4572)
			(layers "F.Cu" "F.Mask" "F.Paste")
			(net "GND")
		)
		(pad "F29" smd circle
			(at 3.800094 -18.050002)
			(size 0.4572 0.4572)
			(layers "F.Cu" "F.Mask" "F.Paste")
			(net "P5E_PEX1_STN5_TX_DN<85>")
		)
		(pad "F30" smd circle
			(at 4.750054 -18.050002)
			(size 0.4572 0.4572)
			(layers "F.Cu" "F.Mask" "F.Paste")
			(net "GND")
		)
		(pad "F31" smd circle
			(at 5.700014 -18.050002)
			(size 0.4572 0.4572)
			(layers "F.Cu" "F.Mask" "F.Paste")
			(net "P5E_PEX1_STN5_TX_DN<87>")
		)
		(pad "F32" smd circle
			(at 6.649974 -18.050002)
			(size 0.4572 0.4572)
			(layers "F.Cu" "F.Mask" "F.Paste")
			(net "GND")
		)
		(pad "F33" smd circle
			(at 7.599934 -18.050002)
			(size 0.4572 0.4572)
			(layers "F.Cu" "F.Mask" "F.Paste")
			(net "P5E_PEX1_STN5_TX_DN<89>")
		)
		(pad "F34" smd circle
			(at 8.549894 -18.050002)
			(size 0.4572 0.4572)
			(layers "F.Cu" "F.Mask" "F.Paste")
			(net "GND")
		)
		(pad "F35" smd circle
			(at 9.500108 -18.050002)
			(size 0.4572 0.4572)
			(layers "F.Cu" "F.Mask" "F.Paste")
			(net "P5E_PEX1_STN5_TX_DN<91>")
		)
		(pad "F36" smd circle
			(at 10.450068 -18.050002)
			(size 0.4572 0.4572)
			(layers "F.Cu" "F.Mask" "F.Paste")
			(net "GND")
		)
		(pad "F37" smd circle
			(at 11.400028 -18.050002)
			(size 0.4572 0.4572)
			(layers "F.Cu" "F.Mask" "F.Paste")
			(net "P5E_PEX1_STN5_TX_DN<93>")
		)
		(pad "F38" smd circle
			(at 12.349988 -18.050002)
			(size 0.4572 0.4572)
			(layers "F.Cu" "F.Mask" "F.Paste")
			(net "GND")
		)
		(pad "F39" smd circle
			(at 13.299948 -18.050002)
			(size 0.4572 0.4572)
			(layers "F.Cu" "F.Mask" "F.Paste")
			(net "P5E_PEX1_STN5_TX_DN<95>")
		)
		(pad "F40" smd circle
			(at 14.249908 -18.050002)
			(size 0.4572 0.4572)
			(layers "F.Cu" "F.Mask" "F.Paste")
			(net "GND")
		)
		(pad "F41" smd circle
			(at 15.200122 -18.050002)
			(size 0.4572 0.4572)
			(layers "F.Cu" "F.Mask" "F.Paste")
			(net "P5E_PEX1_STN4_TX_DN<78>")
		)
		(pad "F42" smd circle
			(at 16.150082 -18.050002)
			(size 0.4572 0.4572)
			(layers "F.Cu" "F.Mask" "F.Paste")
			(net "GND")
		)
		(pad "F43" smd circle
			(at 17.100042 -18.050002)
			(size 0.4572 0.4572)
			(layers "F.Cu" "F.Mask" "F.Paste")
			(net "P5E_PEX1_STN4_TX_DN<76>")
		)
		(pad "F44" smd circle
			(at 18.050002 -18.050002)
			(size 0.4572 0.4572)
			(layers "F.Cu" "F.Mask" "F.Paste")
			(net "GND")
		)
		(pad "F45" smd circle
			(at 18.999962 -18.050002)
			(size 0.4572 0.4572)
			(layers "F.Cu" "F.Mask" "F.Paste")
			(net "P5E_PEX1_STN4_TX_DN<74>")
		)
		(pad "F46" smd circle
			(at 19.949922 -18.050002)
			(size 0.4572 0.4572)
			(layers "F.Cu" "F.Mask" "F.Paste")
			(net "GND")
		)
		(pad "F47" smd circle
			(at 20.899882 -18.050002)
			(size 0.4572 0.4572)
			(layers "F.Cu" "F.Mask" "F.Paste")
			(net "P5E_PEX1_STN4_TX_DN<72>")
		)
		(pad "F48" smd circle
			(at 21.850096 -18.050002)
			(size 0.4572 0.4572)
			(layers "F.Cu" "F.Mask" "F.Paste")
			(net "GND")
		)
		(pad "F49" smd circle
			(at 22.800056 -18.050002)
			(size 0.4572 0.4572)
			(layers "F.Cu" "F.Mask" "F.Paste")
			(net "GND")
		)
		(pad "G1" smd circle
			(at -22.800056 -17.100042)
			(size 0.4572 0.4572)
			(layers "F.Cu" "F.Mask" "F.Paste")
			(net "GND")
		)
		(pad "G2" smd circle
			(at -21.850096 -17.100042)
			(size 0.4572 0.4572)
			(layers "F.Cu" "F.Mask" "F.Paste")
			(net "GND")
		)
		(pad "G3" smd circle
			(at -20.899882 -17.100042)
			(size 0.4572 0.4572)
			(layers "F.Cu" "F.Mask" "F.Paste")
			(net "P5E_PEX1_STN7_TX_DP<123>")
		)
		(pad "G4" smd circle
			(at -19.949922 -17.100042)
			(size 0.4572 0.4572)
			(layers "F.Cu" "F.Mask" "F.Paste")
			(net "GND")
		)
		(pad "G5" smd circle
			(at -18.999962 -17.100042)
			(size 0.4572 0.4572)
			(layers "F.Cu" "F.Mask" "F.Paste")
			(net "P5E_PEX1_STN7_TX_DP<125>")
		)
		(pad "G6" smd circle
			(at -18.050002 -17.100042)
			(size 0.4572 0.4572)
			(layers "F.Cu" "F.Mask" "F.Paste")
			(net "GND")
		)
		(pad "G7" smd circle
			(at -17.100042 -17.100042)
			(size 0.4572 0.4572)
			(layers "F.Cu" "F.Mask" "F.Paste")
			(net "P5E_PEX1_STN7_TX_DP<127>")
		)
		(pad "G8" smd circle
			(at -16.150082 -17.100042)
			(size 0.4572 0.4572)
			(layers "F.Cu" "F.Mask" "F.Paste")
			(net "GND")
		)
		(pad "G9" smd circle
			(at -15.200122 -17.100042)
			(size 0.4572 0.4572)
			(layers "F.Cu" "F.Mask" "F.Paste")
			(net "P5E_PEX1_STN6_TX_DP<110>")
		)
		(pad "G10" smd circle
			(at -14.249908 -17.100042)
			(size 0.4572 0.4572)
			(layers "F.Cu" "F.Mask" "F.Paste")
			(net "GND")
		)
		(pad "G11" smd circle
			(at -13.299948 -17.100042)
			(size 0.4572 0.4572)
			(layers "F.Cu" "F.Mask" "F.Paste")
			(net "P5E_PEX1_STN6_TX_DP<108>")
		)
		(pad "G12" smd circle
			(at -12.349988 -17.100042)
			(size 0.4572 0.4572)
			(layers "F.Cu" "F.Mask" "F.Paste")
			(net "GND")
		)
		(pad "G13" smd circle
			(at -11.400028 -17.100042)
			(size 0.4572 0.4572)
			(layers "F.Cu" "F.Mask" "F.Paste")
			(net "P5E_PEX1_STN6_TX_DP<106>")
		)
		(pad "G14" smd circle
			(at -10.450068 -17.100042)
			(size 0.4572 0.4572)
			(layers "F.Cu" "F.Mask" "F.Paste")
			(net "GND")
		)
		(pad "G15" smd circle
			(at -9.500108 -17.100042)
			(size 0.4572 0.4572)
			(layers "F.Cu" "F.Mask" "F.Paste")
			(net "P5E_PEX1_STN6_TX_DP<104>")
		)
		(pad "G16" smd circle
			(at -8.549894 -17.100042)
			(size 0.4572 0.4572)
			(layers "F.Cu" "F.Mask" "F.Paste")
			(net "GND")
		)
		(pad "G17" smd circle
			(at -7.599934 -17.100042)
			(size 0.4572 0.4572)
			(layers "F.Cu" "F.Mask" "F.Paste")
			(net "P5E_PEX1_STN6_TX_DP<102>")
		)
		(pad "G18" smd circle
			(at -6.649974 -17.100042)
			(size 0.4572 0.4572)
			(layers "F.Cu" "F.Mask" "F.Paste")
			(net "GND")
		)
		(pad "G19" smd circle
			(at -5.700014 -17.100042)
			(size 0.4572 0.4572)
			(layers "F.Cu" "F.Mask" "F.Paste")
			(net "P5E_PEX1_STN6_TX_DP<100>")
		)
		(pad "G20" smd circle
			(at -4.750054 -17.100042)
			(size 0.4572 0.4572)
			(layers "F.Cu" "F.Mask" "F.Paste")
			(net "GND")
		)
		(pad "G21" smd circle
			(at -3.800094 -17.100042)
			(size 0.4572 0.4572)
			(layers "F.Cu" "F.Mask" "F.Paste")
			(net "P5E_PEX1_STN6_TX_DP<98>")
		)
		(pad "G22" smd circle
			(at -2.84988 -17.100042)
			(size 0.4572 0.4572)
			(layers "F.Cu" "F.Mask" "F.Paste")
			(net "GND")
		)
		(pad "G23" smd circle
			(at -1.89992 -17.100042)
			(size 0.4572 0.4572)
			(layers "F.Cu" "F.Mask" "F.Paste")
			(net "P5E_PEX1_STN6_TX_DP<96>")
		)
		(pad "G24" smd circle
			(at -0.94996 -17.100042)
			(size 0.4572 0.4572)
			(layers "F.Cu" "F.Mask" "F.Paste")
			(net "GND")
		)
		(pad "G25" smd circle
			(at 0 -17.100042)
			(size 0.4572 0.4572)
			(layers "F.Cu" "F.Mask" "F.Paste")
			(net "P5E_PEX1_STN5_TX_DP<81>")
		)
		(pad "G26" smd circle
			(at 0.94996 -17.100042)
			(size 0.4572 0.4572)
			(layers "F.Cu" "F.Mask" "F.Paste")
			(net "GND")
		)
		(pad "G27" smd circle
			(at 1.89992 -17.100042)
			(size 0.4572 0.4572)
			(layers "F.Cu" "F.Mask" "F.Paste")
			(net "P5E_PEX1_STN5_TX_DP<83>")
		)
		(pad "G28" smd circle
			(at 2.84988 -17.100042)
			(size 0.4572 0.4572)
			(layers "F.Cu" "F.Mask" "F.Paste")
			(net "GND")
		)
		(pad "G29" smd circle
			(at 3.800094 -17.100042)
			(size 0.4572 0.4572)
			(layers "F.Cu" "F.Mask" "F.Paste")
			(net "P5E_PEX1_STN5_TX_DP<85>")
		)
		(pad "G30" smd circle
			(at 4.750054 -17.100042)
			(size 0.4572 0.4572)
			(layers "F.Cu" "F.Mask" "F.Paste")
			(net "GND")
		)
		(pad "G31" smd circle
			(at 5.700014 -17.100042)
			(size 0.4572 0.4572)
			(layers "F.Cu" "F.Mask" "F.Paste")
			(net "P5E_PEX1_STN5_TX_DP<87>")
		)
		(pad "G32" smd circle
			(at 6.649974 -17.100042)
			(size 0.4572 0.4572)
			(layers "F.Cu" "F.Mask" "F.Paste")
			(net "GND")
		)
		(pad "G33" smd circle
			(at 7.599934 -17.100042)
			(size 0.4572 0.4572)
			(layers "F.Cu" "F.Mask" "F.Paste")
			(net "P5E_PEX1_STN5_TX_DP<89>")
		)
		(pad "G34" smd circle
			(at 8.549894 -17.100042)
			(size 0.4572 0.4572)
			(layers "F.Cu" "F.Mask" "F.Paste")
			(net "GND")
		)
		(pad "G35" smd circle
			(at 9.500108 -17.100042)
			(size 0.4572 0.4572)
			(layers "F.Cu" "F.Mask" "F.Paste")
			(net "P5E_PEX1_STN5_TX_DP<91>")
		)
		(pad "G36" smd circle
			(at 10.450068 -17.100042)
			(size 0.4572 0.4572)
			(layers "F.Cu" "F.Mask" "F.Paste")
			(net "GND")
		)
		(pad "G37" smd circle
			(at 11.400028 -17.100042)
			(size 0.4572 0.4572)
			(layers "F.Cu" "F.Mask" "F.Paste")
			(net "P5E_PEX1_STN5_TX_DP<93>")
		)
		(pad "G38" smd circle
			(at 12.349988 -17.100042)
			(size 0.4572 0.4572)
			(layers "F.Cu" "F.Mask" "F.Paste")
			(net "GND")
		)
		(pad "G39" smd circle
			(at 13.299948 -17.100042)
			(size 0.4572 0.4572)
			(layers "F.Cu" "F.Mask" "F.Paste")
			(net "P5E_PEX1_STN5_TX_DP<95>")
		)
		(pad "G40" smd circle
			(at 14.249908 -17.100042)
			(size 0.4572 0.4572)
			(layers "F.Cu" "F.Mask" "F.Paste")
			(net "GND")
		)
		(pad "G41" smd circle
			(at 15.200122 -17.100042)
			(size 0.4572 0.4572)
			(layers "F.Cu" "F.Mask" "F.Paste")
			(net "P5E_PEX1_STN4_TX_DP<78>")
		)
		(pad "G42" smd circle
			(at 16.150082 -17.100042)
			(size 0.4572 0.4572)
			(layers "F.Cu" "F.Mask" "F.Paste")
			(net "GND")
		)
		(pad "G43" smd circle
			(at 17.100042 -17.100042)
			(size 0.4572 0.4572)
			(layers "F.Cu" "F.Mask" "F.Paste")
			(net "P5E_PEX1_STN4_TX_DP<76>")
		)
		(pad "G44" smd circle
			(at 18.050002 -17.100042)
			(size 0.4572 0.4572)
			(layers "F.Cu" "F.Mask" "F.Paste")
			(net "GND")
		)
		(pad "G45" smd circle
			(at 18.999962 -17.100042)
			(size 0.4572 0.4572)
			(layers "F.Cu" "F.Mask" "F.Paste")
			(net "P5E_PEX1_STN4_TX_DP<74>")
		)
		(pad "G46" smd circle
			(at 19.949922 -17.100042)
			(size 0.4572 0.4572)
			(layers "F.Cu" "F.Mask" "F.Paste")
			(net "GND")
		)
		(pad "G47" smd circle
			(at 20.899882 -17.100042)
			(size 0.4572 0.4572)
			(layers "F.Cu" "F.Mask" "F.Paste")
			(net "P5E_PEX1_STN4_TX_DP<72>")
		)
		(pad "G48" smd circle
			(at 21.850096 -17.100042)
			(size 0.4572 0.4572)
			(layers "F.Cu" "F.Mask" "F.Paste")
			(net "GND")
		)
		(pad "G49" smd circle
			(at 22.800056 -17.100042)
			(size 0.4572 0.4572)
			(layers "F.Cu" "F.Mask" "F.Paste")
			(net "GND")
		)
		(pad "H1" smd circle
			(at -22.800056 -16.150082)
			(size 0.4572 0.4572)
			(layers "F.Cu" "F.Mask" "F.Paste")
			(net "P5E_PEX1_STN7_TX_DN<121>")
		)
		(pad "H2" smd circle
			(at -21.850096 -16.150082)
			(size 0.4572 0.4572)
			(layers "F.Cu" "F.Mask" "F.Paste")
			(net "P5E_PEX1_STN7_TX_DP<121>")
		)
		(pad "H3" smd circle
			(at -20.899882 -16.150082)
			(size 0.4572 0.4572)
			(layers "F.Cu" "F.Mask" "F.Paste")
			(net "GND")
		)
		(pad "H4" smd circle
			(at -19.949922 -16.150082)
			(size 0.4572 0.4572)
			(layers "F.Cu" "F.Mask" "F.Paste")
			(net "P5E_PEX1_STN7_TX_DN<124>")
		)
		(pad "H5" smd circle
			(at -18.999962 -16.150082)
			(size 0.4572 0.4572)
			(layers "F.Cu" "F.Mask" "F.Paste")
			(net "GND")
		)
		(pad "H6" smd circle
			(at -18.050002 -16.150082)
			(size 0.4572 0.4572)
			(layers "F.Cu" "F.Mask" "F.Paste")
			(net "P5E_PEX1_STN7_TX_DN<126>")
		)
		(pad "H7" smd circle
			(at -17.100042 -16.150082)
			(size 0.4572 0.4572)
			(layers "F.Cu" "F.Mask" "F.Paste")
			(net "GND")
		)
	)
)
